(kicad_pcb
	(version 20260206)
	(generator "pcbnew")
	(generator_version "10.0")
	(general
		(thickness 1.6)
		(legacy_teardrops no)
	)
	(paper "A4")
	(title_block
		(title "fcb — 12433-1M.1206WZS1330.brd")
		(comment 1 "Open Vault / Knox (Wiwynn) / footprints 216-222 of 495")
	)
	(layers
		(0 "F.Cu" signal "TOP")
		(4 "In1.Cu" signal "L2GND")
		(6 "In2.Cu" signal "L3VCC")
		(2 "B.Cu" signal "BOTTOM")
		(9 "F.Adhes" user "F.Adhesive")
		(11 "B.Adhes" user "B.Adhesive")
		(13 "F.Paste" user "Package Geometry/Pastemask Top")
		(15 "B.Paste" user "Package Geometry/Pastemask Bottom")
		(5 "F.SilkS" user "Ref Des/Silkscreen Top")
		(7 "B.SilkS" user "Ref Des/Silkscreen Bottom")
		(1 "F.Mask" user "Board Geometry/Soldermask Top")
		(3 "B.Mask" user "Board Geometry/Soldermask Bottom")
		(17 "Dwgs.User" user "User.Drawings")
		(19 "Cmts.User" user "User.Comments")
		(21 "Eco1.User" user "User.Eco1")
		(23 "Eco2.User" user "User.Eco2")
		(25 "Edge.Cuts" user "Board Geometry/Outline")
		(27 "Margin" user)
		(31 "F.CrtYd" user "Package Geometry/Place Bound Top")
		(29 "B.CrtYd" user "Package Geometry/Place Bound Bottom")
		(35 "F.Fab" user "Ref Des/Assembly Top")
		(33 "B.Fab" user "Ref Des/Assembly Bottom")
	)
	(footprint ""
		(layer "F.Cu")
		(at 36.068 -252.603 -90)
		(property "Reference" "TP18"
			(at 0 0 270)
			(layer "F.SilkS")
			(hide yes)
			(effects
				(font
					(size 1.27 1.27)
				)
			)
		)
		(property "Value" "TPAD32-GP"
			(at 0 -3.166364 270)
			(unlocked yes)
			(layer "F.Fab")
			(hide yes)
			(effects
				(font
					(size 1.016 1.016)
					(thickness 0.1524)
				)
			)
		)
		(property "Device Type" "TPAD32"
			(at 0 -4.690618 270)
			(unlocked yes)
			(layer "F.Fab")
			(hide yes)
			(effects
				(font
					(size 1.016 1.016)
					(thickness 0.1524)
				)
			)
		)
		(duplicate_pad_numbers_are_jumpers no)
		(fp_poly
			(pts
				(arc
					(start 0.7112 0)
					(mid -0.7112 0)
					(end 0.7112 0)
				)
			)
			(stroke
				(width 0)
				(type default)
			)
			(fill no)
			(layer "F.CrtYd")
		)
		(fp_poly
			(pts
				(arc
					(start 0.7112 0)
					(mid -0.7112 0)
					(end 0.7112 0)
				)
			)
			(stroke
				(width 0)
				(type default)
			)
			(fill no)
			(layer "F.Fab")
		)
		(pad "1" smd circle
			(at 0 0 270)
			(size 0.8128 0.8128)
			(layers "F.Cu" "F.Mask" "F.Paste")
			(net "LED_DRV_RST")
		)
	)
	(footprint ""
		(layer "F.Cu")
		(at 39.878 -240.665 180)
		(property "Reference" "R155"
			(at 0 0 180)
			(layer "F.SilkS")
			(hide yes)
			(effects
				(font
					(size 1.27 1.27)
				)
			)
		)
		(property "Value" "330R2J-3-GP"
			(at 0.064008 -3.993896 180)
			(unlocked yes)
			(layer "F.Fab")
			(hide yes)
			(effects
				(font
					(size 1.016 1.016)
					(thickness 0.1524)
				)
			)
		)
		(property "Device Type" "R402H16"
			(at 0.064008 -5.517896 180)
			(unlocked yes)
			(layer "F.Fab")
			(hide yes)
			(effects
				(font
					(size 1.016 1.016)
					(thickness 0.1524)
				)
			)
		)
		(duplicate_pad_numbers_are_jumpers no)
		(fp_line
			(start 0.508 -0.9398)
			(end -0.508 -0.9398)
			(stroke
				(width 0.1524)
				(type default)
			)
			(layer "F.SilkS")
		)
		(fp_line
			(start -0.508 -0.9398)
			(end -0.508 0.9398)
			(stroke
				(width 0.1524)
				(type default)
			)
			(layer "F.SilkS")
		)
		(fp_rect
			(start -0.508 0.9398)
			(end 0.508 -0.9398)
			(stroke
				(width 0)
				(type default)
			)
			(fill no)
			(layer "F.CrtYd")
		)
		(fp_rect
			(start -0.508 0.9398)
			(end 0.508 -0.9398)
			(stroke
				(width 0)
				(type default)
			)
			(fill no)
			(layer "F.Fab")
		)
		(pad "1" smd custom
			(at 0 -0.4445 180)
			(size 0.1397 0.1397)
			(layers "F.Cu" "F.Mask" "F.Paste")
			(net "P3V3")
			(options
				(clearance outline)
				(anchor circle)
			)
			(primitives
				(gr_poly
					(pts
						(arc
							(start -0.1778 -0.2794)
							(mid -0.249642 -0.249642)
							(end -0.2794 -0.1778)
						)
						(arc
							(start -0.2794 0.1778)
							(mid -0.249642 0.249642)
							(end -0.1778 0.2794)
						)
						(arc
							(start 0.1778 0.2794)
							(mid 0.249642 0.249642)
							(end 0.2794 0.1778)
						)
						(arc
							(start 0.2794 -0.1778)
							(mid 0.249642 -0.249642)
							(end 0.1778 -0.2794)
						)
					)
					(width 0)
					(fill yes)
				)
			)
		)
		(pad "2" smd custom
			(at 0 0.4445 180)
			(size 0.1397 0.1397)
			(layers "F.Cu" "F.Mask" "F.Paste")
			(net "LED_DR_LED3")
			(options
				(clearance outline)
				(anchor circle)
			)
			(primitives
				(gr_poly
					(pts
						(arc
							(start -0.1778 -0.2794)
							(mid -0.249642 -0.249642)
							(end -0.2794 -0.1778)
						)
						(arc
							(start -0.2794 0.1778)
							(mid -0.249642 0.249642)
							(end -0.1778 0.2794)
						)
						(arc
							(start 0.1778 0.2794)
							(mid 0.249642 0.249642)
							(end 0.2794 0.1778)
						)
						(arc
							(start 0.2794 -0.1778)
							(mid 0.249642 -0.249642)
							(end 0.1778 -0.2794)
						)
					)
					(width 0)
					(fill yes)
				)
			)
		)
	)
	(footprint ""
		(layer "F.Cu")
		(at 19.1262 -241.1984 90)
		(property "Reference" "PL7"
			(at 0 0 90)
			(layer "F.SilkS")
			(hide yes)
			(effects
				(font
					(size 1.27 1.27)
				)
			)
		)
		(property "Value" "IND-22UH-169-GP"
			(at -4.7498 0.5588 90)
			(unlocked yes)
			(layer "F.Fab")
			(hide yes)
			(effects
				(font
					(size 1.016 1.016)
					(thickness 0.1524)
				)
			)
		)
		(property "Device Type" "L6362-D620H119"
			(at -4.7498 -0.9652 90)
			(unlocked yes)
			(layer "F.Fab")
			(hide yes)
			(effects
				(font
					(size 1.016 1.016)
					(thickness 0.1524)
				)
			)
		)
		(duplicate_pad_numbers_are_jumpers no)
		(fp_line
			(start 1.667256 -3.8989)
			(end 3.3528 -2.213356)
			(stroke
				(width 0.1524)
				(type default)
			)
			(layer "F.SilkS")
		)
		(fp_line
			(start -1.667256 -3.8989)
			(end 1.667256 -3.8989)
			(stroke
				(width 0.1524)
				(type default)
			)
			(layer "F.SilkS")
		)
		(fp_line
			(start 3.3528 -2.213356)
			(end 3.3528 2.213356)
			(stroke
				(width 0.1524)
				(type default)
			)
			(layer "F.SilkS")
		)
		(fp_line
			(start -3.3528 -2.213356)
			(end -1.667256 -3.8989)
			(stroke
				(width 0.1524)
				(type default)
			)
			(layer "F.SilkS")
		)
		(fp_line
			(start 3.3528 2.213356)
			(end 1.667256 3.8989)
			(stroke
				(width 0.1524)
				(type default)
			)
			(layer "F.SilkS")
		)
		(fp_line
			(start -3.3528 2.213356)
			(end -3.3528 -2.213356)
			(stroke
				(width 0.1524)
				(type default)
			)
			(layer "F.SilkS")
		)
		(fp_line
			(start 1.667256 3.8989)
			(end -1.667256 3.8989)
			(stroke
				(width 0.1524)
				(type default)
			)
			(layer "F.SilkS")
		)
		(fp_line
			(start -1.667256 3.8989)
			(end -3.3528 2.213356)
			(stroke
				(width 0.1524)
				(type default)
			)
			(layer "F.SilkS")
		)
		(fp_poly
			(pts
				(xy 2.0574 3.1496) (xy -2.0574 3.1496) (xy -3.0988 2.1082) (xy -3.0988 -2.1082) (xy -2.0574 -3.1496)
				(xy 2.0574 -3.1496) (xy 3.0988 -2.1082) (xy 3.0988 2.1082)
			)
			(stroke
				(width 0)
				(type default)
			)
			(fill no)
			(layer "F.CrtYd")
		)
		(fp_poly
			(pts
				(xy 3.6068 2.318512) (xy 1.950212 3.9751) (xy -1.950212 3.9751) (xy -3.6068 2.318512) (xy -3.6068 -2.318512)
				(xy -1.950212 -3.9751) (xy 1.950212 -3.9751) (xy 3.6068 -2.318512) (xy 3.6068 -1.9177) (xy 3.0988 -1.9177)
				(xy 3.0988 -2.1082) (xy 2.0574 -3.1496) (xy -2.0574 -3.1496) (xy -3.0988 -2.1082) (xy -3.0988 2.1082)
				(xy -2.0574 3.1496) (xy 2.0574 3.1496) (xy 3.0988 2.1082) (xy 3.0988 -1.905) (xy 3.6068 -1.905)
			)
			(stroke
				(width 0)
				(type default)
			)
			(fill no)
			(layer "F.CrtYd")
		)
		(fp_poly
			(pts
				(xy -1.950212 3.9751) (xy -3.6068 2.318512) (xy -3.6068 -2.318512) (xy -1.950212 -3.9751) (xy 1.950212 -3.9751)
				(xy 3.6068 -2.318512) (xy 3.6068 2.318512) (xy 1.950212 3.9751)
			)
			(stroke
				(width 0)
				(type default)
			)
			(fill no)
			(layer "F.Fab")
		)
		(pad "1" smd rect
			(at 0 -2.895346 90)
			(size 2.2606 1.4986)
			(layers "F.Cu" "F.Mask" "F.Paste")
			(net "P3V3_LX")
		)
		(pad "2" smd rect
			(at 0 2.895346 90)
			(size 2.2606 1.4986)
			(layers "F.Cu" "F.Mask" "F.Paste")
			(net "P3V3_LX_COPPER")
		)
	)
	(footprint ""
		(layer "F.Cu")
		(at 18.288 -271.7038 90)
		(property "Reference" "R179"
			(at 0 0 90)
			(layer "F.SilkS")
			(hide yes)
			(effects
				(font
					(size 1.27 1.27)
				)
			)
		)
		(property "Value" "0R1206-PAD-1-GP"
			(at 0 -5.0292 90)
			(unlocked yes)
			(layer "F.Fab")
			(hide yes)
			(effects
				(font
					(size 1.016 1.016)
					(thickness 0.1524)
				)
			)
		)
		(property "Device Type" "0R1206-PAD-1"
			(at 0 -6.5532 90)
			(unlocked yes)
			(layer "F.Fab")
			(hide yes)
			(effects
				(font
					(size 1.016 1.016)
					(thickness 0.1524)
				)
			)
		)
		(duplicate_pad_numbers_are_jumpers no)
		(fp_line
			(start 1.016 -2.2352)
			(end -1.016 -2.2352)
			(stroke
				(width 0.1524)
				(type default)
			)
			(layer "F.SilkS")
		)
		(fp_line
			(start -1.016 -2.2352)
			(end -1.016 2.2352)
			(stroke
				(width 0.1524)
				(type default)
			)
			(layer "F.SilkS")
		)
		(fp_line
			(start 1.016 2.2352)
			(end 1.016 -2.2352)
			(stroke
				(width 0.1524)
				(type default)
			)
			(layer "F.SilkS")
		)
		(fp_line
			(start -1.016 2.2352)
			(end 1.016 2.2352)
			(stroke
				(width 0.1524)
				(type default)
			)
			(layer "F.SilkS")
		)
		(fp_rect
			(start -1.0922 2.3114)
			(end 1.0922 -2.3114)
			(stroke
				(width 0)
				(type default)
			)
			(fill no)
			(layer "F.CrtYd")
		)
		(fp_poly
			(pts
				(xy -1.0922 -2.3114) (xy 1.0922 -2.3114) (xy 1.0922 2.3114) (xy -1.0922 2.3114)
			)
			(stroke
				(width 0)
				(type default)
			)
			(fill no)
			(layer "F.Fab")
		)
		(pad "1" smd rect
			(at 0 -1.397 90)
			(size 1.651 2.0574)
			(drill
				(offset 0 0.3937)
			)
			(layers "F.Cu" "F.Mask" "F.Paste")
			(net "P12V_FAN3")
		)
		(pad "2" smd rect
			(at 0 1.397 90)
			(size 1.651 2.0574)
			(drill
				(offset 0 -0.3937)
			)
			(layers "F.Cu" "F.Mask" "F.Paste")
			(net "P12V")
		)
	)
	(footprint ""
		(layer "F.Cu")
		(at 32.385 -361.315 180)
		(property "Reference" "R108"
			(at 0 0 180)
			(layer "F.SilkS")
			(hide yes)
			(effects
				(font
					(size 1.27 1.27)
				)
			)
		)
		(property "Value" "0R2J-2-GP"
			(at 0.064008 -3.993896 180)
			(unlocked yes)
			(layer "F.Fab")
			(hide yes)
			(effects
				(font
					(size 1.016 1.016)
					(thickness 0.1524)
				)
			)
		)
		(property "Device Type" "R402H16"
			(at 0.064008 -5.517896 180)
			(unlocked yes)
			(layer "F.Fab")
			(hide yes)
			(effects
				(font
					(size 1.016 1.016)
					(thickness 0.1524)
				)
			)
		)
		(duplicate_pad_numbers_are_jumpers no)
		(fp_line
			(start 0.508 -0.9398)
			(end -0.508 -0.9398)
			(stroke
				(width 0.1524)
				(type default)
			)
			(layer "F.SilkS")
		)
		(fp_line
			(start -0.508 -0.9398)
			(end -0.508 0.9398)
			(stroke
				(width 0.1524)
				(type default)
			)
			(layer "F.SilkS")
		)
		(fp_rect
			(start -0.508 0.9398)
			(end 0.508 -0.9398)
			(stroke
				(width 0)
				(type default)
			)
			(fill no)
			(layer "F.CrtYd")
		)
		(fp_rect
			(start -0.508 0.9398)
			(end 0.508 -0.9398)
			(stroke
				(width 0)
				(type default)
			)
			(fill no)
			(layer "F.Fab")
		)
		(pad "1" smd custom
			(at 0 -0.4445 180)
			(size 0.1397 0.1397)
			(layers "F.Cu" "F.Mask" "F.Paste")
			(net "I2C_C_SCL")
			(options
				(clearance outline)
				(anchor circle)
			)
			(primitives
				(gr_poly
					(pts
						(arc
							(start -0.1778 -0.2794)
							(mid -0.249642 -0.249642)
							(end -0.2794 -0.1778)
						)
						(arc
							(start -0.2794 0.1778)
							(mid -0.249642 0.249642)
							(end -0.1778 0.2794)
						)
						(arc
							(start 0.1778 0.2794)
							(mid 0.249642 0.249642)
							(end 0.2794 0.1778)
						)
						(arc
							(start 0.2794 -0.1778)
							(mid 0.249642 -0.249642)
							(end 0.1778 -0.2794)
						)
					)
					(width 0)
					(fill yes)
				)
			)
		)
		(pad "2" smd custom
			(at 0 0.4445 180)
			(size 0.1397 0.1397)
			(layers "F.Cu" "F.Mask" "F.Paste")
			(net "I2C_C_SCL_ADM1276")
			(options
				(clearance outline)
				(anchor circle)
			)
			(primitives
				(gr_poly
					(pts
						(arc
							(start -0.1778 -0.2794)
							(mid -0.249642 -0.249642)
							(end -0.2794 -0.1778)
						)
						(arc
							(start -0.2794 0.1778)
							(mid -0.249642 0.249642)
							(end -0.1778 0.2794)
						)
						(arc
							(start 0.1778 0.2794)
							(mid 0.249642 0.249642)
							(end 0.2794 0.1778)
						)
						(arc
							(start 0.2794 -0.1778)
							(mid 0.249642 -0.249642)
							(end 0.1778 -0.2794)
						)
					)
					(width 0)
					(fill yes)
				)
			)
		)
	)
	(footprint ""
		(layer "F.Cu")
		(at 33.147 -376.428 90)
		(property "Reference" "PR14"
			(at 0 0 90)
			(layer "F.SilkS")
			(hide yes)
			(effects
				(font
					(size 1.27 1.27)
				)
			)
		)
		(property "Value" "0R2J-2-GP"
			(at 0.064008 -3.993896 90)
			(unlocked yes)
			(layer "F.Fab")
			(hide yes)
			(effects
				(font
					(size 1.016 1.016)
					(thickness 0.1524)
				)
			)
		)
		(property "Device Type" "R402H16"
			(at 0.064008 -5.517896 90)
			(unlocked yes)
			(layer "F.Fab")
			(hide yes)
			(effects
				(font
					(size 1.016 1.016)
					(thickness 0.1524)
				)
			)
		)
		(duplicate_pad_numbers_are_jumpers no)
		(fp_line
			(start 0.508 -0.9398)
			(end -0.508 -0.9398)
			(stroke
				(width 0.1524)
				(type default)
			)
			(layer "F.SilkS")
		)
		(fp_line
			(start -0.508 -0.9398)
			(end -0.508 0.9398)
			(stroke
				(width 0.1524)
				(type default)
			)
			(layer "F.SilkS")
		)
		(fp_rect
			(start -0.508 0.9398)
			(end 0.508 -0.9398)
			(stroke
				(width 0)
				(type default)
			)
			(fill no)
			(layer "F.CrtYd")
		)
		(fp_rect
			(start -0.508 0.9398)
			(end 0.508 -0.9398)
			(stroke
				(width 0)
				(type default)
			)
			(fill no)
			(layer "F.Fab")
		)
		(pad "1" smd custom
			(at 0 -0.4445 90)
			(size 0.1397 0.1397)
			(layers "F.Cu" "F.Mask" "F.Paste")
			(net "ADM1276_GATE")
			(options
				(clearance outline)
				(anchor circle)
			)
			(primitives
				(gr_poly
					(pts
						(arc
							(start -0.1778 -0.2794)
							(mid -0.249642 -0.249642)
							(end -0.2794 -0.1778)
						)
						(arc
							(start -0.2794 0.1778)
							(mid -0.249642 0.249642)
							(end -0.1778 0.2794)
						)
						(arc
							(start 0.1778 0.2794)
							(mid 0.249642 0.249642)
							(end 0.2794 0.1778)
						)
						(arc
							(start 0.2794 -0.1778)
							(mid 0.249642 -0.249642)
							(end 0.1778 -0.2794)
						)
					)
					(width 0)
					(fill yes)
				)
			)
		)
		(pad "2" smd custom
			(at 0 0.4445 90)
			(size 0.1397 0.1397)
			(layers "F.Cu" "F.Mask" "F.Paste")
			(net "ADM1276_GATE_RC")
			(options
				(clearance outline)
				(anchor circle)
			)
			(primitives
				(gr_poly
					(pts
						(arc
							(start -0.1778 -0.2794)
							(mid -0.249642 -0.249642)
							(end -0.2794 -0.1778)
						)
						(arc
							(start -0.2794 0.1778)
							(mid -0.249642 0.249642)
							(end -0.1778 0.2794)
						)
						(arc
							(start 0.1778 0.2794)
							(mid 0.249642 0.249642)
							(end 0.2794 0.1778)
						)
						(arc
							(start 0.2794 -0.1778)
							(mid 0.249642 -0.249642)
							(end 0.1778 -0.2794)
						)
					)
					(width 0)
					(fill yes)
				)
			)
		)
	)
	(footprint ""
		(layer "F.Cu")
		(at 23.749 -106.426 90)
		(property "Reference" "TC3"
			(at 0 0 90)
			(layer "F.SilkS")
			(hide yes)
			(effects
				(font
					(size 1.27 1.27)
				)
			)
		)
		(property "Value" "ST68U16VDM-1-GP"
			(at 0 -9.6012 90)
			(unlocked yes)
			(layer "F.Fab")
			(hide yes)
			(effects
				(font
					(size 1.016 1.016)
					(thickness 0.1524)
				)
			)
		)
		(property "Device Type" "CT7343H79"
			(at 0 -11.1252 90)
			(unlocked yes)
			(layer "F.Fab")
			(hide yes)
			(effects
				(font
					(size 1.016 1.016)
					(thickness 0.1524)
				)
			)
		)
		(duplicate_pad_numbers_are_jumpers no)
		(fp_line
			(start 2.286 -4.8768)
			(end -2.286 -4.8768)
			(stroke
				(width 0.1524)
				(type default)
			)
			(layer "F.SilkS")
		)
		(fp_line
			(start -2.286 -4.8768)
			(end -2.286 -2.032)
			(stroke
				(width 0.1524)
				(type default)
			)
			(layer "F.SilkS")
		)
		(fp_line
			(start 2.1082 -4.699)
			(end -2.1082 -4.699)
			(stroke
				(width 0.508)
				(type default)
			)
			(layer "F.SilkS")
		)
		(fp_line
			(start 2.286 -2.032)
			(end 2.286 -4.8768)
			(stroke
				(width 0.1524)
				(type default)
			)
			(layer "F.SilkS")
		)
		(fp_line
			(start 2.286 2.032)
			(end 2.286 4.8768)
			(stroke
				(width 0.1524)
				(type default)
			)
			(layer "F.SilkS")
		)
		(fp_line
			(start 2.286 4.8768)
			(end -2.286 4.8768)
			(stroke
				(width 0.1524)
				(type default)
			)
			(layer "F.SilkS")
		)
		(fp_line
			(start -2.286 4.8768)
			(end -2.286 2.032)
			(stroke
				(width 0.1524)
				(type default)
			)
			(layer "F.SilkS")
		)
		(fp_rect
			(start -2.1463 3.6449)
			(end 2.1463 -3.6449)
			(stroke
				(width 0)
				(type default)
			)
			(fill no)
			(layer "F.CrtYd")
		)
		(fp_poly
			(pts
				(xy -2.54 4.953) (xy -2.54 4.2926) (xy -3.81 4.2926) (xy -3.81 -4.2926) (xy -2.54 -4.2926) (xy -2.54 -4.953)
				(xy 2.54 -4.953) (xy 2.54 -4.2926) (xy 3.81 -4.2926) (xy 3.81 -1.6256) (xy 2.1463 -1.6256) (xy 2.1463 -3.6449)
				(xy -2.1463 -3.6449) (xy -2.1463 3.6449) (xy 2.1463 3.6449) (xy 2.1463 -1.6129) (xy 3.81 -1.6129)
				(xy 3.81 4.2926) (xy 2.54 4.2926) (xy 2.54 4.953)
			)
			(stroke
				(width 0)
				(type default)
			)
			(fill no)
			(layer "F.CrtYd")
		)
		(fp_rect
			(start 2.54 4.2926)
			(end 3.81 -4.2926)
			(stroke
				(width 0)
				(type default)
			)
			(fill no)
			(layer "F.Fab")
		)
		(fp_rect
			(start -3.81 4.2926)
			(end -2.54 -4.2926)
			(stroke
				(width 0)
				(type default)
			)
			(fill no)
			(layer "F.Fab")
		)
		(fp_rect
			(start -2.54 4.953)
			(end 2.54 -4.953)
			(stroke
				(width 0)
				(type default)
			)
			(fill no)
			(layer "F.Fab")
		)
		(pad "1" smd rect
			(at 0 -3.1496 90)
			(size 2.413 2.286)
			(layers "F.Cu" "F.Mask" "F.Paste")
			(net "P12VU")
		)
		(pad "2" smd rect
			(at 0 3.1496 90)
			(size 2.413 2.286)
			(layers "F.Cu" "F.Mask" "F.Paste")
			(net "GND")
		)
		(zone
			(layer "F.Cu")
			(hatch none 0.5)
			(connect_pads
				(clearance 0)
			)
			(min_thickness 0.25)
			(keepout
				(tracks allowed)
				(vias not_allowed)
				(pads allowed)
				(copperpour not_allowed)
				(footprints allowed)
			)
			(placement
				(enabled no)
				(sheetname "")
			)
			(fill
				(thermal_gap 0.5)
				(thermal_bridge_width 0.5)
				(island_removal_mode 0)
			)
			(polygon
				(pts
					(xy 22.0599 -107.9373) (xy 19.1516 -107.9373) (xy 19.1516 -104.9147) (xy 22.0472 -104.9147) (xy 22.3774 -104.9147)
					(xy 22.3774 -107.9373)
				)
			)
		)
		(zone
			(layer "F.Cu")
			(hatch none 0.5)
			(connect_pads
				(clearance 0)
			)
			(min_thickness 0.25)
			(keepout
				(tracks allowed)
				(vias not_allowed)
				(pads allowed)
				(copperpour not_allowed)
				(footprints allowed)
			)
			(placement
				(enabled no)
				(sheetname "")
			)
			(fill
				(thermal_gap 0.5)
				(thermal_bridge_width 0.5)
				(island_removal_mode 0)
			)
			(polygon
				(pts
					(xy 28.3464 -104.9147) (xy 28.3464 -107.9373) (xy 25.4508 -107.9373) (xy 25.1206 -107.9373) (xy 25.1206 -104.9147)
					(xy 25.4508 -104.9147)
				)
			)
		)
	)
)
